(kicad_pcb
	(version 20260206)
	(generator "pcbnew")
	(generator_version "10.0")
	(general
		(thickness 1.6)
		(legacy_teardrops no)
	)
	(paper "A4")
	(title_block
		(title "timecard-production-celestica-r4006 — R4006-B0001-02_R01.brd")
		(comment 1 "Time Appliance Project (Time Card) / footprints 567-573 of 1113")
	)
	(layers
		(0 "F.Cu" signal "TOP")
		(4 "In1.Cu" signal "L02_GND1")
		(6 "In2.Cu" signal "L03_SIG1")
		(8 "In3.Cu" signal "L04_GND2")
		(10 "In4.Cu" signal "L05_VCC1")
		(12 "In5.Cu" signal "L06_VCC2")
		(14 "In6.Cu" signal "L07_GND3")
		(16 "In7.Cu" signal "L08_SIG2")
		(18 "In8.Cu" signal "L09_GND4")
		(2 "B.Cu" signal "BOTTOM")
		(9 "F.Adhes" user "F.Adhesive")
		(11 "B.Adhes" user "B.Adhesive")
		(13 "F.Paste" user "Package Geometry/Pastemask Top")
		(15 "B.Paste" user "Package Geometry/Pastemask Bottom")
		(5 "F.SilkS" user "Ref Des/Silkscreen Top")
		(7 "B.SilkS" user "Ref Des/Silkscreen Bottom")
		(1 "F.Mask" user "Board Geometry/Soldermask Top")
		(3 "B.Mask" user "Board Geometry/Soldermask Bottom")
		(17 "Dwgs.User" user "User.Drawings")
		(19 "Cmts.User" user "User.Comments")
		(21 "Eco1.User" user "User.Eco1")
		(23 "Eco2.User" user "User.Eco2")
		(25 "Edge.Cuts" user "Board Geometry/Outline")
		(27 "Margin" user)
		(31 "F.CrtYd" user "Package Geometry/Place Bound Top")
		(29 "B.CrtYd" user "Package Geometry/Place Bound Bottom")
		(35 "F.Fab" user "Ref Des/Assembly Top")
		(33 "B.Fab" user "Ref Des/Assembly Bottom")
	)
	(footprint ""
		(layer "F.Cu")
		(at 74.0918 -84.6328)
		(property "Reference" "R311"
			(at -0.1778 -3.33883 0)
			(unlocked yes)
			(layer "F.SilkS")
			(effects
				(font
					(size 0.7874 0.5842)
					(thickness 0.1524)
				)
			)
		)
		(property "Value" "VAL*"
			(at 0.02032 2.13233 0)
			(unlocked yes)
			(layer "F.Fab")
			(hide yes)
			(effects
				(font
					(size 0.7874 0.5842)
					(thickness 0.1524)
				)
			)
		)
		(property "Tolerance" "TOL*"
			(at 0.044704 3.05435 0)
			(unlocked yes)
			(layer "Cmts.User")
			(hide yes)
			(effects
				(font
					(size 0.7874 0.5842)
					(thickness 0.1524)
				)
			)
		)
		(property "User Part Number" "PARTNUM*"
			(at 0.02032 4.024884 0)
			(unlocked yes)
			(layer "Cmts.User")
			(hide yes)
			(effects
				(font
					(size 0.7874 0.5842)
					(thickness 0.1524)
				)
			)
		)
		(property "Device Type" "RESISTOR-G155-100R0-J0,0OHM,-"
			(at 0.008382 1.210564 0)
			(unlocked yes)
			(layer "F.Fab")
			(hide yes)
			(effects
				(font
					(size 0.7874 0.5842)
					(thickness 0.1524)
				)
			)
		)
		(duplicate_pad_numbers_are_jumpers no)
		(fp_line
			(start -1.143 -0.5588)
			(end -1.143 0.5588)
			(stroke
				(width 0.1)
				(type default)
			)
			(layer "F.SilkS")
		)
		(fp_line
			(start -1.143 0.5588)
			(end 1.143 0.5588)
			(stroke
				(width 0.1)
				(type default)
			)
			(layer "F.SilkS")
		)
		(fp_line
			(start 1.143 -0.5588)
			(end -1.143 -0.5588)
			(stroke
				(width 0.1)
				(type default)
			)
			(layer "F.SilkS")
		)
		(fp_line
			(start 1.143 0.5588)
			(end 1.143 -0.5588)
			(stroke
				(width 0.1)
				(type default)
			)
			(layer "F.SilkS")
		)
		(fp_poly
			(pts
				(xy -1.143 0.5588) (xy 1.143 0.5588) (xy 1.143 -0.5588) (xy -1.143 -0.5588)
			)
			(stroke
				(width 0)
				(type default)
			)
			(fill no)
			(layer "F.CrtYd")
		)
		(fp_line
			(start -0.508 -0.3048)
			(end -0.508 0.3048)
			(stroke
				(width 0.1)
				(type default)
			)
			(layer "F.Fab")
		)
		(fp_line
			(start -0.508 0.3048)
			(end 0.508 0.3048)
			(stroke
				(width 0.1)
				(type default)
			)
			(layer "F.Fab")
		)
		(fp_line
			(start 0.508 -0.3048)
			(end -0.508 -0.3048)
			(stroke
				(width 0.1)
				(type default)
			)
			(layer "F.Fab")
		)
		(fp_line
			(start 0.508 0.3048)
			(end 0.508 -0.3048)
			(stroke
				(width 0.1)
				(type default)
			)
			(layer "F.Fab")
		)
		(pad "1" smd rect
			(at -0.5334 0)
			(size 0.7112 0.6096)
			(layers "F.Cu" "F.Mask" "F.Paste")
			(net "RGB_LED_I2C_SCL")
		)
		(pad "2" smd rect
			(at 0.5334 0)
			(size 0.7112 0.6096)
			(layers "F.Cu" "F.Mask" "F.Paste")
			(net "R_PCA9546_I2C_SCL")
		)
		(zone
			(layer "F.Cu")
			(hatch none 0.5)
			(connect_pads
				(clearance 0)
			)
			(min_thickness 0.25)
			(keepout
				(tracks not_allowed)
				(vias allowed)
				(pads allowed)
				(copperpour not_allowed)
				(footprints allowed)
			)
			(placement
				(enabled no)
				(sheetname "")
			)
			(fill
				(thermal_gap 0.5)
				(thermal_bridge_width 0.5)
				(island_removal_mode 0)
			)
			(polygon
				(pts
					(xy 74.0156 -84.328) (xy 74.168 -84.328) (xy 74.168 -84.9376) (xy 74.0156 -84.9376)
				)
			)
		)
		(zone
			(layer "F.Cu")
			(hatch none 0.5)
			(connect_pads
				(clearance 0)
			)
			(min_thickness 0.25)
			(keepout
				(tracks allowed)
				(vias not_allowed)
				(pads allowed)
				(copperpour not_allowed)
				(footprints allowed)
			)
			(placement
				(enabled no)
				(sheetname "")
			)
			(fill
				(thermal_gap 0.5)
				(thermal_bridge_width 0.5)
				(island_removal_mode 0)
			)
			(polygon
				(pts
					(xy 74.0156 -84.328) (xy 74.168 -84.328) (xy 74.168 -84.9376) (xy 74.0156 -84.9376)
				)
			)
		)
	)
	(footprint ""
		(layer "F.Cu")
		(at 121.793 -23.495)
		(property "Reference" "TP12"
			(at -0.2032 -1.67005 0)
			(unlocked yes)
			(layer "F.SilkS")
			(effects
				(font
					(size 0.635 0.4064)
					(thickness 0.1524)
				)
				(justify left)
			)
		)
		(property "Value" ""
			(at 0 0 0)
			(layer "F.Fab")
			(effects
				(font
					(size 1.27 1.27)
				)
			)
		)
		(property "Device Type" "TP_PIONT-TP010CT020B030_PTH-TPA"
			(at -1.341882 0.996696 0)
			(unlocked yes)
			(layer "F.Fab")
			(hide yes)
			(effects
				(font
					(size 0.7874 0.5842)
					(thickness 0.000001)
				)
				(justify left)
			)
		)
		(duplicate_pad_numbers_are_jumpers no)
		(fp_poly
			(pts
				(arc
					(start 0.889 0)
					(mid -0.889 0)
					(end 0.889 0)
				)
			)
			(stroke
				(width 0)
				(type default)
			)
			(fill no)
			(layer "B.CrtYd")
		)
		(fp_poly
			(pts
				(arc
					(start 0.889 0)
					(mid -0.889 0)
					(end 0.889 0)
				)
			)
			(stroke
				(width 0)
				(type default)
			)
			(fill no)
			(layer "F.CrtYd")
		)
		(pad "1" thru_hole circle
			(at 0 0)
			(size 0.508 0.508)
			(drill 0.254)
			(layers "*.Cu" "*.Mask")
			(remove_unused_layers no)
			(net "MUX3_SEL")
			(clearance 0.1016)
			(padstack
				(mode front_inner_back)
				(layer "Inner"
					(shape circle)
					(size 0.508 0.508)
					(clearance 0.1016)
				)
				(layer "B.Cu"
					(shape circle)
					(size 0.762 0.762)
					(clearance -0.0254)
				)
			)
		)
	)
	(footprint ""
		(layer "F.Cu")
		(at 74.0664 -81.4324 180)
		(property "Reference" "C38"
			(at 0.5334 4.50723 0)
			(unlocked yes)
			(layer "F.SilkS")
			(effects
				(font
					(size 0.7874 0.5842)
					(thickness 0.1524)
				)
			)
		)
		(property "Value" "VAL*"
			(at 0.0762 2.067306 180)
			(unlocked yes)
			(layer "F.Fab")
			(hide yes)
			(effects
				(font
					(size 0.7874 0.5842)
					(thickness 0.1524)
				)
			)
		)
		(property "Tolerance" "TOL*"
			(at 0.0762 3.032506 180)
			(unlocked yes)
			(layer "Cmts.User")
			(hide yes)
			(effects
				(font
					(size 0.7874 0.5842)
					(thickness 0.1524)
				)
			)
		)
		(property "User Part Number" "PARTNUM*"
			(at 0.1016 4.023106 180)
			(unlocked yes)
			(layer "Cmts.User")
			(hide yes)
			(effects
				(font
					(size 0.7874 0.5842)
					(thickness 0.1524)
				)
			)
		)
		(property "Device Type" "CAPACITOR-G105-0B104-CK,0.1UF,A"
			(at 0.0508 1.127506 180)
			(unlocked yes)
			(layer "F.Fab")
			(hide yes)
			(effects
				(font
					(size 0.7874 0.5842)
					(thickness 0.1524)
				)
			)
		)
		(duplicate_pad_numbers_are_jumpers no)
		(fp_line
			(start 1.143 0.5588)
			(end 1.143 -0.5588)
			(stroke
				(width 0.1)
				(type default)
			)
			(layer "F.SilkS")
		)
		(fp_line
			(start 1.143 -0.5588)
			(end -1.143 -0.5588)
			(stroke
				(width 0.1)
				(type default)
			)
			(layer "F.SilkS")
		)
		(fp_line
			(start -1.143 0.5588)
			(end 1.143 0.5588)
			(stroke
				(width 0.1)
				(type default)
			)
			(layer "F.SilkS")
		)
		(fp_line
			(start -1.143 -0.5588)
			(end -1.143 0.5588)
			(stroke
				(width 0.1)
				(type default)
			)
			(layer "F.SilkS")
		)
		(fp_rect
			(start 1.143 0.5588)
			(end -1.143 -0.5588)
			(stroke
				(width 0)
				(type default)
			)
			(fill no)
			(layer "F.CrtYd")
		)
		(fp_line
			(start 0.508 0.3048)
			(end 0.508 -0.3048)
			(stroke
				(width 0.1)
				(type default)
			)
			(layer "F.Fab")
		)
		(fp_line
			(start 0.508 -0.3048)
			(end -0.508 -0.3048)
			(stroke
				(width 0.1)
				(type default)
			)
			(layer "F.Fab")
		)
		(fp_line
			(start -0.508 0.3048)
			(end 0.508 0.3048)
			(stroke
				(width 0.1)
				(type default)
			)
			(layer "F.Fab")
		)
		(fp_line
			(start -0.508 -0.3048)
			(end -0.508 0.3048)
			(stroke
				(width 0.1)
				(type default)
			)
			(layer "F.Fab")
		)
		(pad "1" smd rect
			(at -0.5334 0 180)
			(size 0.7112 0.6096)
			(layers "F.Cu" "F.Mask" "F.Paste")
			(net "VDD_PCA9546A")
		)
		(pad "2" smd rect
			(at 0.5334 0 180)
			(size 0.7112 0.6096)
			(layers "F.Cu" "F.Mask" "F.Paste")
			(net "SG")
		)
		(zone
			(layer "F.Cu")
			(hatch none 0.5)
			(connect_pads
				(clearance 0)
			)
			(min_thickness 0.25)
			(keepout
				(tracks allowed)
				(vias not_allowed)
				(pads allowed)
				(copperpour not_allowed)
				(footprints allowed)
			)
			(placement
				(enabled no)
				(sheetname "")
			)
			(fill
				(thermal_gap 0.5)
				(thermal_bridge_width 0.5)
				(island_removal_mode 0)
			)
			(polygon
				(pts
					(xy 73.9902 -81.7372) (xy 73.9902 -81.1276) (xy 74.1426 -81.1276) (xy 74.1426 -81.7372)
				)
			)
		)
	)
	(footprint ""
		(layer "F.Cu")
		(at 55.2704 -98.1964 -90)
		(property "Reference" "C12"
			(at -0.127 -3.59537 90)
			(unlocked yes)
			(layer "F.SilkS")
			(effects
				(font
					(size 0.7874 0.5842)
					(thickness 0.1524)
				)
			)
		)
		(property "Value" "VAL*"
			(at 0.0762 2.067306 270)
			(unlocked yes)
			(layer "F.Fab")
			(hide yes)
			(effects
				(font
					(size 0.7874 0.5842)
					(thickness 0.1524)
				)
			)
		)
		(property "Device Type" "CAPACITOR-G105-0B104-CK,0.1UF,A"
			(at 0.0508 1.127506 270)
			(unlocked yes)
			(layer "F.Fab")
			(hide yes)
			(effects
				(font
					(size 0.7874 0.5842)
					(thickness 0.1524)
				)
			)
		)
		(property "User Part Number" "PARTNUM*"
			(at 0.1016 4.023106 270)
			(unlocked yes)
			(layer "Cmts.User")
			(hide yes)
			(effects
				(font
					(size 0.7874 0.5842)
					(thickness 0.1524)
				)
			)
		)
		(property "Tolerance" "TOL*"
			(at 0.0762 3.032506 270)
			(unlocked yes)
			(layer "Cmts.User")
			(hide yes)
			(effects
				(font
					(size 0.7874 0.5842)
					(thickness 0.1524)
				)
			)
		)
		(duplicate_pad_numbers_are_jumpers no)
		(fp_line
			(start -1.143 0.5588)
			(end 1.143 0.5588)
			(stroke
				(width 0.1)
				(type default)
			)
			(layer "F.SilkS")
		)
		(fp_line
			(start 1.143 0.5588)
			(end 1.143 -0.5588)
			(stroke
				(width 0.1)
				(type default)
			)
			(layer "F.SilkS")
		)
		(fp_line
			(start -1.143 -0.5588)
			(end -1.143 0.5588)
			(stroke
				(width 0.1)
				(type default)
			)
			(layer "F.SilkS")
		)
		(fp_line
			(start 1.143 -0.5588)
			(end -1.143 -0.5588)
			(stroke
				(width 0.1)
				(type default)
			)
			(layer "F.SilkS")
		)
		(fp_rect
			(start -1.143 -0.5588)
			(end 1.143 0.5588)
			(stroke
				(width 0)
				(type default)
			)
			(fill no)
			(layer "F.CrtYd")
		)
		(fp_line
			(start -0.508 0.3048)
			(end 0.508 0.3048)
			(stroke
				(width 0.1)
				(type default)
			)
			(layer "F.Fab")
		)
		(fp_line
			(start 0.508 0.3048)
			(end 0.508 -0.3048)
			(stroke
				(width 0.1)
				(type default)
			)
			(layer "F.Fab")
		)
		(fp_line
			(start -0.508 -0.3048)
			(end -0.508 0.3048)
			(stroke
				(width 0.1)
				(type default)
			)
			(layer "F.Fab")
		)
		(fp_line
			(start 0.508 -0.3048)
			(end -0.508 -0.3048)
			(stroke
				(width 0.1)
				(type default)
			)
			(layer "F.Fab")
		)
		(pad "1" smd rect
			(at -0.5334 0 270)
			(size 0.7112 0.6096)
			(layers "F.Cu" "F.Mask" "F.Paste")
			(net "XP5R0V")
		)
		(pad "2" smd rect
			(at 0.5334 0 270)
			(size 0.7112 0.6096)
			(layers "F.Cu" "F.Mask" "F.Paste")
			(net "SG")
		)
		(zone
			(layer "F.Cu")
			(hatch none 0.5)
			(connect_pads
				(clearance 0)
			)
			(min_thickness 0.25)
			(keepout
				(tracks allowed)
				(vias not_allowed)
				(pads allowed)
				(copperpour not_allowed)
				(footprints allowed)
			)
			(placement
				(enabled no)
				(sheetname "")
			)
			(fill
				(thermal_gap 0.5)
				(thermal_bridge_width 0.5)
				(island_removal_mode 0)
			)
			(polygon
				(pts
					(xy 55.5752 -98.2726) (xy 54.9656 -98.2726) (xy 54.9656 -98.1202) (xy 55.5752 -98.1202)
				)
			)
		)
	)
	(footprint ""
		(layer "F.Cu")
		(at 124.841 -37.719)
		(property "Reference" "TP139"
			(at -2.00025 2.2098 90)
			(unlocked yes)
			(layer "F.SilkS")
			(effects
				(font
					(size 0.635 0.4064)
					(thickness 0.1524)
				)
				(justify left)
			)
		)
		(property "Value" ""
			(at 0 0 0)
			(layer "F.Fab")
			(effects
				(font
					(size 1.27 1.27)
				)
			)
		)
		(property "Device Type" "TP_PIONT-TP010CT020B030_PTH-TPA"
			(at -1.341882 0.996696 0)
			(unlocked yes)
			(layer "F.Fab")
			(hide yes)
			(effects
				(font
					(size 0.7874 0.5842)
					(thickness 0.1524)
				)
				(justify left)
			)
		)
		(duplicate_pad_numbers_are_jumpers no)
		(fp_poly
			(pts
				(arc
					(start 0.889 0)
					(mid -0.889 0)
					(end 0.889 0)
				)
			)
			(stroke
				(width 0)
				(type default)
			)
			(fill no)
			(layer "B.CrtYd")
		)
		(fp_poly
			(pts
				(arc
					(start 0.889 0)
					(mid -0.889 0)
					(end 0.889 0)
				)
			)
			(stroke
				(width 0)
				(type default)
			)
			(fill no)
			(layer "F.CrtYd")
		)
		(pad "1" thru_hole circle
			(at 0 0)
			(size 0.508 0.508)
			(drill 0.254)
			(layers "*.Cu" "*.Mask")
			(remove_unused_layers no)
			(net "IO_L23N_34")
			(clearance 0.1016)
			(padstack
				(mode front_inner_back)
				(layer "Inner"
					(shape circle)
					(size 0.508 0.508)
					(clearance 0.1016)
				)
				(layer "B.Cu"
					(shape circle)
					(size 0.762 0.762)
					(clearance -0.0254)
				)
			)
		)
	)
	(footprint ""
		(layer "F.Cu")
		(at 48.006 -131.445)
		(property "Reference" "SP62"
			(at 0 0 0)
			(layer "F.SilkS")
			(hide yes)
			(effects
				(font
					(size 1.27 1.27)
				)
			)
		)
		(property "Value" ""
			(at 0 0 0)
			(layer "F.Fab")
			(effects
				(font
					(size 1.27 1.27)
				)
			)
		)
		(duplicate_pad_numbers_are_jumpers no)
	)
	(footprint ""
		(layer "F.Cu")
		(at 74.0664 -82.7786)
		(property "Reference" "R310"
			(at -0.1524 -4.17703 0)
			(unlocked yes)
			(layer "F.SilkS")
			(effects
				(font
					(size 0.7874 0.5842)
					(thickness 0.1524)
				)
			)
		)
		(property "Value" "VAL*"
			(at 0.02032 2.13233 0)
			(unlocked yes)
			(layer "F.Fab")
			(hide yes)
			(effects
				(font
					(size 0.7874 0.5842)
					(thickness 0.1524)
				)
			)
		)
		(property "Tolerance" "TOL*"
			(at 0.044704 3.05435 0)
			(unlocked yes)
			(layer "Cmts.User")
			(hide yes)
			(effects
				(font
					(size 0.7874 0.5842)
					(thickness 0.1524)
				)
			)
		)
		(property "User Part Number" "PARTNUM*"
			(at 0.02032 4.024884 0)
			(unlocked yes)
			(layer "Cmts.User")
			(hide yes)
			(effects
				(font
					(size 0.7874 0.5842)
					(thickness 0.1524)
				)
			)
		)
		(property "Device Type" "RESISTOR-G155-100R0-J0,0OHM,-"
			(at 0.008382 1.210564 0)
			(unlocked yes)
			(layer "F.Fab")
			(hide yes)
			(effects
				(font
					(size 0.7874 0.5842)
					(thickness 0.1524)
				)
			)
		)
		(duplicate_pad_numbers_are_jumpers no)
		(fp_line
			(start -1.143 -0.5588)
			(end -1.143 0.5588)
			(stroke
				(width 0.1)
				(type default)
			)
			(layer "F.SilkS")
		)
		(fp_line
			(start -1.143 0.5588)
			(end 1.143 0.5588)
			(stroke
				(width 0.1)
				(type default)
			)
			(layer "F.SilkS")
		)
		(fp_line
			(start 1.143 -0.5588)
			(end -1.143 -0.5588)
			(stroke
				(width 0.1)
				(type default)
			)
			(layer "F.SilkS")
		)
		(fp_line
			(start 1.143 0.5588)
			(end 1.143 -0.5588)
			(stroke
				(width 0.1)
				(type default)
			)
			(layer "F.SilkS")
		)
		(fp_poly
			(pts
				(xy -1.143 0.5588) (xy 1.143 0.5588) (xy 1.143 -0.5588) (xy -1.143 -0.5588)
			)
			(stroke
				(width 0)
				(type default)
			)
			(fill no)
			(layer "F.CrtYd")
		)
		(fp_line
			(start -0.508 -0.3048)
			(end -0.508 0.3048)
			(stroke
				(width 0.1)
				(type default)
			)
			(layer "F.Fab")
		)
		(fp_line
			(start -0.508 0.3048)
			(end 0.508 0.3048)
			(stroke
				(width 0.1)
				(type default)
			)
			(layer "F.Fab")
		)
		(fp_line
			(start 0.508 -0.3048)
			(end -0.508 -0.3048)
			(stroke
				(width 0.1)
				(type default)
			)
			(layer "F.Fab")
		)
		(fp_line
			(start 0.508 0.3048)
			(end 0.508 -0.3048)
			(stroke
				(width 0.1)
				(type default)
			)
			(layer "F.Fab")
		)
		(pad "1" smd rect
			(at -0.5334 0)
			(size 0.7112 0.6096)
			(layers "F.Cu" "F.Mask" "F.Paste")
			(net "RGB_LED_I2C_SDA")
		)
		(pad "2" smd rect
			(at 0.5334 0)
			(size 0.7112 0.6096)
			(layers "F.Cu" "F.Mask" "F.Paste")
			(net "R_PCA9546_I2C_SDA")
		)
		(zone
			(layer "F.Cu")
			(hatch none 0.5)
			(connect_pads
				(clearance 0)
			)
			(min_thickness 0.25)
			(keepout
				(tracks not_allowed)
				(vias allowed)
				(pads allowed)
				(copperpour not_allowed)
				(footprints allowed)
			)
			(placement
				(enabled no)
				(sheetname "")
			)
			(fill
				(thermal_gap 0.5)
				(thermal_bridge_width 0.5)
				(island_removal_mode 0)
			)
			(polygon
				(pts
					(xy 73.9902 -82.4738) (xy 74.1426 -82.4738) (xy 74.1426 -83.0834) (xy 73.9902 -83.0834)
				)
			)
		)
		(zone
			(layer "F.Cu")
			(hatch none 0.5)
			(connect_pads
				(clearance 0)
			)
			(min_thickness 0.25)
			(keepout
				(tracks allowed)
				(vias not_allowed)
				(pads allowed)
				(copperpour not_allowed)
				(footprints allowed)
			)
			(placement
				(enabled no)
				(sheetname "")
			)
			(fill
				(thermal_gap 0.5)
				(thermal_bridge_width 0.5)
				(island_removal_mode 0)
			)
			(polygon
				(pts
					(xy 73.9902 -82.4738) (xy 74.1426 -82.4738) (xy 74.1426 -83.0834) (xy 73.9902 -83.0834)
				)
			)
		)
	)
)
